FILE_TYPE = MULTI_PHYS_TABLE;

PART 'MOSFET_N_GSD'

{========================================================================================}
:VALUE            | PART_TYPE | MATERIAL | PART_NUMBER       = STANDARD        | LIFECYCLE      | PART_NUMBER       | JEDEC_TYPE               | DESCRIPTION                                | MANUFTR | MANUF_PN         | RD_CMPLS_LVL | CMPLS_LVL | CLASS | DIP_SMD | FP_ECN              | FROM_PJ         | DATA                            | EE_CHECK_LIST | PSL | PREFERENCE | CREATOR | CREATEDAY  | STATUS ;
{========================================================================================}
 'IPB027N10N3 G'  | 'SMLF'    | 'IC'     | 'BAM027N0000'(!)  = 'End of Design' | 'Comp-Approve' | 'BAM027N0000'     |'TO263_GDSXA'| 'TRANS MOS IPB027N10N3 G(100V,120A,300W)'  | 'SNI'   | 'IPB027N10N3 G'  | 'EP(V1)'     | ''        | 'IC'  | ''      | ''                  | 'T2L-CHEESE'    | 'SNI_IPB027N10N3-G.pdf'         | ''            | ''  | ''         | ''      | '20120203' | ''    
 'IPB027N10N3 G'  | 'SMLF'    | 'EMPTY'  | 'BAM027N0000'(!)  = 'End of Design' | 'Comp-Approve' | 'BAM027N0000'     |'TO263_GDSXA'| 'TRANS MOS IPB027N10N3 G(100V,120A,300W)'  | 'SNI'   | 'IPB027N10N3 G'  | 'EP(V1)'     | ''        | 'IC'  | ''      | ''                  | 'T2L-CHEESE'    | 'SNI_IPB027N10N3-G.pdf'         | ''            | ''  | ''         | ''      | '20120203' | ''    
 'DMG6968U-7'     | 'SMLF'    | 'IC'     | 'BAM69680000'(!)  = 'End of Design' | 'Comp-Approve' | 'BAM69680000'     |'SOT23_GDSXC'| 'TRANS MOS DMG6968U-7(20V,6.5A,1.3W)SOT23' | 'DDS'   | 'DMG6968U-7'     | 'EP(V1)'     | ''        | 'IC'  | ''      | ''                  | 'S1N-AI-JU'     | 'DDS_DMG6968U.pdf'              | ''            | ''  | ''         | ''      | '20120801' | ''    
 'DMG6968U-7'     | 'SMLF'    | 'EMPTY'  | 'BAM69680000'(!)  = 'End of Design' | 'Comp-Approve' | 'BAM69680000'     |'SOT23_GDSXC'| 'TRANS MOS DMG6968U-7(20V,6.5A,1.3W)SOT23' | 'DDS'   | 'DMG6968U-7'     | 'EP(V1)'     | ''        | 'IC'  | ''      | ''                  | 'S1N-AI-JU'     | 'DDS_DMG6968U.pdf'              | ''            | ''  | ''         | ''      | '20120801' | ''    
 'NX7002AK'       | 'SMLF'    | 'IC'     | 'BAM70020062'(!)  = 'End of Design' | 'Comp-Approve' | 'BAM70020062'     |'SOT23_GDSXE'| 'TRANS MOS NX7002AK(60V,0.19A,0.325W)SMD'  | 'NXP'   | 'NX7002AK'       | 'EP(V1)'     | ''        | 'IC'  | ''      | ''                  | 'S1N-AI-JU'     | 'NXP_NX7002AK.pdf'              | ''            | ''  | ''         | ''      | '20120801' | ''    
 'NX7002AK'       | 'SMLF'    | 'EMPTY'  | 'BAM70020062'(!)  = 'End of Design' | 'Comp-Approve' | 'BAM70020062'     |'SOT23_GDSXE'| 'TRANS MOS NX7002AK(60V,0.19A,0.325W)SMD'  | 'NXP'   | 'NX7002AK'       | 'EP(V1)'     | ''        | 'IC'  | ''      | ''                  | 'S1N-AI-JU'     | 'NXP_NX7002AK.pdf'              | ''            | ''  | ''         | ''      | '20120801' | ''    
 'DMN5L06K-7'     | 'SMLF'    | 'IC'     | 'BA05L060000'(!)  = ''              | 'End of Life'  | 'BA05L060000'     |'SOT23_GDSXC_EOL'| 'TRANS SMD DMN5L06K-7(50V,0.3A)SOT-23'     | 'DDS'   | 'DMN5L06K-7'     | 'EP(V1)'     | 'EP(V1)'  | 'IC'  | ''      | ''                  | 'S1D-OZ'        | 'DDS_DMN5L06K.pdf'              | ''            | ''  | ''         | ''      | '20120921' | ''    
 'DMN5L06K-7'     | 'SMLF'    | 'EMPTY'  | 'BA05L060000'(!)  = ''              | 'End of Life'  | 'BA05L060000'     |'SOT23_GDSXC_EOL'| 'TRANS SMD DMN5L06K-7(50V,0.3A)SOT-23'     | 'DDS'   | 'DMN5L06K-7'     | 'EP(V1)'     | 'EP(V1)'  | 'IC'  | ''      | ''                  | 'S1D-OZ'        | 'DDS_DMN5L06K.pdf'              | ''            | ''  | ''         | ''      | '20120921' | ''    
 'DMN601K-7'      | 'SMLF'    | 'IC'     | 'BAM601K0003'(!)  = 'End of Design' | ''             | 'BAM601K0003'     |'SOT23_GDSXC'| 'TRANS MOSFET DMN601K-7(60V,300MA)SOT-23'  | 'DDS'   | 'DMN601K-7'      | 'EP(V1)'     | 'EP(V1)'  | 'IC'  | ''      | ''                  | 'S4LZ-ROGER'    | 'DDS_DMN601K-7.pdf'             | ''            | ''  | ''         | ''      | '20140502' | ''    
 'DMN601K-7'      | 'SMLF'    | 'EMPTY'  | 'BAM601K0003'(!)  = 'End of Design' | ''             | 'BAM601K0003'     |'SOT23_GDSXC'| 'TRANS MOSFET DMN601K-7(60V,300MA)SOT-23'  | 'DDS'   | 'DMN601K-7'      | 'EP(V1)'     | 'EP(V1)'  | 'IC'  | ''      | ''                  | 'S4LZ-ROGER'    | 'DDS_DMN601K-7.pdf'             | ''            | ''  | ''         | ''      | '20140502' | ''    
 'NTR4501NT1G'    | 'SMLF'    | 'IC'     | 'BAM45010052'(!)  = 'End of Design' | 'Comp-Approve' | 'BAM45010052'     |'SOT23_GDSXC'| 'TRANS MOS NTR4501NT1G(20V,SOT-23)'        | 'ONS'   | 'NTR4501NT1G'    | 'EP(V1)'     | 'EP(V1)'  | 'IC'  | ''      | ''                  | 'T2H-GAVEN'     | 'ONS_NTR4501N_REV4.pdf'         | ''            | ''  | ''         | ''      | '20140808' | ''    
 'NTR4501NT1G'    | 'SMLF'    | 'EMPTY'  | 'BAM45010052'(!)  = 'End of Design' | 'Comp-Approve' | 'BAM45010052'     |'SOT23_GDSXC'| 'TRANS MOS NTR4501NT1G(20V,SOT-23)'        | 'ONS'   | 'NTR4501NT1G'    | 'EP(V1)'     | 'EP(V1)'  | 'IC'  | ''      | ''                  | 'T2H-GAVEN'     | 'ONS_NTR4501N_REV4.pdf'         | ''            | ''  | ''         | ''      | '20140808' | ''    
 'BSS138-7-F'     | 'SMLF'    | 'IC'     | 'BAM01380016'(!)  = ''              | ''             | 'BAM01380016'     |'SOT23_GDSXC'| 'TRANS MOSFET BSS138-7-F(50V,0.2A)'        | 'DDS'   | 'BSS138-7-F'     | 'EP(V1)'     | 'EP(V1)'  | 'IC'  | ''      | ''                  | 'MF2-CHIA-LU'   | 'DDS_BSS138-7-F.pdf'            | ''            | ''  | ''         | ''      | '20150728' | ''    
 'BSS138-7-F'     | 'SMLF'    | 'EMPTY'  | 'BAM01380016'(!)  = ''              | ''             | 'BAM01380016'     |'SOT23_GDSXC'| 'TRANS MOSFET BSS138-7-F(50V,0.2A)'        | 'DDS'   | 'BSS138-7-F'     | 'EP(V1)'     | 'EP(V1)'  | 'IC'  | ''      | ''                  | 'MF2-CHIA-LU'   | 'DDS_BSS138-7-F.pdf'            | ''            | ''  | ''         | ''      | '20150728' | ''    
 'FDB047N10'      | 'SMLF'    | 'IC'     | 'BAM00470000'(!)  = ''              | ''             | 'BAM00470000'     |'TO263_GDSXB'| 'TRANS MOS FDB047N10(100V,164A,375W)'      | 'FAC'   | 'FDB047N10'      | 'EP(V1)'     | ''        | 'IC'  | ''      | ''                  | 'T2H-HSUEH-YEN' | 'FAC_FDB047N10.pdf'             | ''            | ''  | ''         | ''      | '20151207' | ''    
 'FDB047N10'      | 'SMLF'    | 'EMPTY'  | 'BAM00470000'(!)  = ''              | ''             | 'BAM00470000'     |'TO263_GDSXB'| 'TRANS MOS FDB047N10(100V,164A,375W)'      | 'FAC'   | 'FDB047N10'      | 'EP(V1)'     | ''        | 'IC'  | ''      | ''                  | 'T2H-HSUEH-YEN' | 'FAC_FDB047N10.pdf'             | ''            | ''  | ''         | ''      | '20151207' | ''    
 'AO7400'         | 'SMLF'    | 'IC'     | 'BAM74000000'(!)  = ''              | ''             | 'BAM74000000'     |'SC70_GDS_2X1-25'| 'TRANSISTOR MOSFET AO7400(30V,1.7A)SC70'   | 'AOS'   | 'AO7400'         | 'EU(V1)'     | 'EU(V1)'  | 'IC'  | ''      | ''                  | 'S5B-ROSSI'     | 'AOS_AO7400.pdf'                | ''            | ''  | ''         | ''      | '20151230' | ''    
 'AO7400'         | 'SMLF'    | 'EMPTY'  | 'BAM74000000'(!)  = ''              | ''             | 'BAM74000000'     |'SC70_GDS_2X1-25'| 'TRANSISTOR MOSFET AO7400(30V,1.7A)SC70'   | 'AOS'   | 'AO7400'         | 'EU(V1)'     | 'EU(V1)'  | 'IC'  | ''      | ''                  | 'S5B-ROSSI'     | 'AOS_AO7400.pdf'                | ''            | ''  | ''         | ''      | '20151230' | ''    
 'NX138BK'        | 'SMLF'    | 'IC'     | 'BAM01380023'(!)  = ''              | ''             | 'BAM01380023'     |'SOT23_GDSXE'| 'TRANS MOS NX138BK(60V,265MA,310MW)'       | 'NXP'   | 'NX138BK'        | 'EP(V1)'     | ''        | 'IC'  | ''      | ''                  | 'T2H-CF'        | 'NXP_NX138BK.pdf'               | ''            | ''  | ''         | ''      | '20160322' | ''    
 'NX138BK'        | 'SMLF'    | 'EMPTY'  | 'BAM01380023'(!)  = ''              | ''             | 'BAM01380023'     |'SOT23_GDSXE'| 'TRANS MOS NX138BK(60V,265MA,310MW)'       | 'NXP'   | 'NX138BK'        | 'EP(V1)'     | ''        | 'IC'  | ''      | ''                  | 'T2H-CF'        | 'NXP_NX138BK.pdf'               | ''            | ''  | ''         | ''      | '20160322' | ''    
 'NX7002BK'       | 'SMLF'    | 'IC'     | 'BAM70020063'(!)  = ''              | ''             | 'BAM70020063'     |'SOT23_GDSXE'| 'TRANS MOSFET NX7002BK(60V,0.27A,0.31W)'   | 'NXP'   | 'NX7002BK'       | 'EP(V1)'     | 'EP(V1)'  | 'IC'  | ''      | ''                  | 'JBW-WILLIAM'   | 'NXP_NX7002BK.pdf'              | ''            | ''  | ''         | ''      | '20161021' | ''    
 'NX7002BK'       | 'SMLF'    | 'EMPTY'  | 'BAM70020063'(!)  = ''              | ''             | 'BAM70020063'     |'SOT23_GDSXE'| 'TRANS MOSFET NX7002BK(60V,0.27A,0.31W)'   | 'NXP'   | 'NX7002BK'       | 'EP(V1)'     | 'EP(V1)'  | 'IC'  | ''      | ''                  | 'JBW-WILLIAM'   | 'NXP_NX7002BK.pdf'              | ''            | ''  | ''         | ''      | '20161021' | ''    
 'CSD19536KTT'    | 'SMLF'    | 'IC'     | 'BAM19530001'(!)  = ''              | ''             | 'BAM19530001'     |'TO263_GDSXC'| 'TRANS MOS CSD19536KTT(100V,200A,375W)'    | 'TIC'   | 'CSD19536KTT'    | 'EP(V1)'     | ''        | 'IC'  | ''      | ''                  | 'T2H-HSUEH-YEN' | 'TIC_CSD19536KTT.pdf'           | ''            | ''  | ''         | ''      | '20170105' | ''    
 'CSD19536KTT'    | 'SMLF'    | 'EMPTY'  | 'BAM19530001'(!)  = ''              | ''             | 'BAM19530001'     |'TO263_GDSXC'| 'TRANS MOS CSD19536KTT(100V,200A,375W)'    | 'TIC'   | 'CSD19536KTT'    | 'EP(V1)'     | ''        | 'IC'  | ''      | ''                  | 'T2H-HSUEH-YEN' | 'TIC_CSD19536KTT.pdf'           | ''            | ''  | ''         | ''      | '20170105' | ''    
 'CSD17484F4'     | 'SMLF'    | 'IC'     | 'BAM17480000'(!)  = ''              | ''             | 'BAM17480000'     |'PICOSTAR_GDS'| 'TRANS MOS CSD17484F4(30V,3A,0.5W)'        | 'TIC'   | 'CSD17484F4'     | 'EP(V1)'     | ''        | 'IC'  | ''      | ''                  | 'F08-TOM'       | 'TIC_CSD17484F4.pdf'            | ''            | ''  | ''         | ''      | '20170411' | ''    
 'CSD17484F4'     | 'SMLF'    | 'EMPTY'  | 'BAM17480000'(!)  = ''              | ''             | 'BAM17480000'     |'PICOSTAR_GDS'| 'TRANS MOS CSD17484F4(30V,3A,0.5W)'        | 'TIC'   | 'CSD17484F4'     | 'EP(V1)'     | ''        | 'IC'  | ''      | ''                  | 'F08-TOM'       | 'TIC_CSD17484F4.pdf'            | ''            | ''  | ''         | ''      | '20170411' | ''    
 'AO3442'         | 'SMLF'    | 'IC'     | 'BAM34420000'(!)  = ''              | ''             | 'BAM34420000'     |'SOT23_GDSXA'| 'TRANS MOS AO3442(100V,1A,1.4W):SOT23'     | 'AOS'   | 'AO3442'         | 'EP(V1)'     | ''        | 'IC'  | ''      | ''                  | 'T2H-HSUEH-YEN' | 'AOS_AO3442.pdf'                | ''            | ''  | ''         | ''      | '20170612' | ''    
 'AO3442'         | 'SMLF'    | 'EMPTY'  | 'BAM34420000'(!)  = ''              | ''             | 'BAM34420000'     |'SOT23_GDSXA'| 'TRANS MOS AO3442(100V,1A,1.4W):SOT23'     | 'AOS'   | 'AO3442'         | 'EP(V1)'     | ''        | 'IC'  | ''      | ''                  | 'T2H-HSUEH-YEN' | 'AOS_AO3442.pdf'                | ''            | ''  | ''         | ''      | '20170612' | ''    
 'PSMN4R8-100BSE' | 'SMLF'    | 'IC'     | 'BAMN4R80000'(!)  = ''              | ''             | 'BAMN4R80000'     |'SOT404_GDSXA'| 'TRANS MOS PSMN4R8-100BSE(100V,120A,405W)' | 'NXP'   | 'PSMN4R8-100BSE' | 'EU(V1)'     | 'EU(V1)'  | 'IC'  | ''      | ''                  | 'UH3M-CARLOS'   | 'NXP_PSMN4R8-100BSE.pdf'        | ''            | ''  | ''         | ''      | '20170803' | ''    
 'PSMN4R8-100BSE' | 'SMLF'    | 'EMPTY'  | 'BAMN4R80000'(!)  = ''              | ''             | 'BAMN4R80000'     |'SOT404_GDSXA'| 'TRANS MOS PSMN4R8-100BSE(100V,120A,405W)' | 'NXP'   | 'PSMN4R8-100BSE' | 'EU(V1)'     | 'EU(V1)'  | 'IC'  | ''      | ''                  | 'UH3M-CARLOS'   | 'NXP_PSMN4R8-100BSE.pdf'        | ''            | ''  | ''         | ''      | '20170803' | ''    
 'IXFT320N10T2'   | 'SMLF'    | 'IC'     | 'BAM320N0000'(!)  = ''              | ''             | 'BAM320N0000'     |'TO268'| 'TRANS MOS IXFT320N10T2(100V,320A,1000W)'  | 'IYS'   | 'IXFT320N10T2'   | 'EP(V1)'     | ''        | 'IC'  | ''      | ''                  | 'T2N-JANE'      | 'IXFH320N10T2-IXFT320N10T2.pdf' | ''            | ''  | ''         | ''      | '20170816' | ''    
 'IXFT320N10T2'   | 'SMLF'    | 'EMPTY'  | 'BAM320N0000'(!)  = ''              | ''             | 'BAM320N0000'     |'TO268'| 'TRANS MOS IXFT320N10T2(100V,320A,1000W)'  | 'IYS'   | 'IXFT320N10T2'   | 'EP(V1)'     | ''        | 'IC'  | ''      | ''                  | 'T2N-JANE'      | 'IXFH320N10T2-IXFT320N10T2.pdf' | ''            | ''  | ''         | ''      | '20170816' | ''    
 'FDN357N'        | 'SMLF'    | 'IC'     | 'BAM03570Z05'(!)  = 'End of Design' | 'Comp-Approve' | 'BAM03570Z05'     |'SOT23_GDS'| 'TRANSISTOR MOSFET FDN357N(30V.1.9A.SOT23' | 'FAC'   | 'FDN357N'        | 'EP(V1)'     | 'EP(V1)'  | 'IC'  | ''      | ''                  | 'JG5-TOM'       | 'FDN357N.pdf'                   | ''            | ''  | ''         | ''      | '20180813' | ''    
 'FDN357N'        | 'SMLF'    | 'EMPTY'  | 'BAM03570Z05'(!)  = 'End of Design' | 'Comp-Approve' | 'BAM03570Z05'     |'SOT23_GDS'| 'TRANSISTOR MOSFET FDN357N(30V.1.9A.SOT23' | 'FAC'   | 'FDN357N'        | 'EP(V1)'     | 'EP(V1)'  | 'IC'  | ''      | ''                  | 'JG5-TOM'       | 'FDN357N.pdf'                   | ''            | ''  | ''         | ''      | '20180813' | ''    
 'FDB035N10A'     | 'SMLF'    | 'IC'     | 'BAM00350004'(!)  = ''              | ''             | 'BAM00350004'     |'TO263_GDSXB'| 'TRANS MOS FDB035N10A(100V,214A,333W)'     | 'FAC'   | 'FDB035N10A'     | 'EP(V1)'     | 'EP(V1)'  | 'IC'  | ''      | ''                  | 'JPB-CARLOS'    | 'FAC_FDB035N10A.pdf'            | ''            | ''  | ''         | ''      | '20190115' | ''    
 'FDB035N10A'     | 'SMLF'    | 'EMPTY'  | 'BAM00350004'(!)  = ''              | ''             | 'BAM00350004'     |'TO263_GDSXB'| 'TRANS MOS FDB035N10A(100V,214A,333W)'     | 'FAC'   | 'FDB035N10A'     | 'EP(V1)'     | 'EP(V1)'  | 'IC'  | ''      | ''                  | 'JPB-CARLOS'    | 'FAC_FDB035N10A.pdf'            | ''            | ''  | ''         | ''      | '20190115' | ''    
 'IPB033N10N5LF'  | 'SMLF'    | 'IC'     | 'BAM10N50G01'(!)  = ''              | ''             | 'BAM10N50G01'     |'TO263_GDSXA'| 'TRANS MOS IPB033N10N5LF(100V,120A,179W)'  | 'SNI'   | 'IPB033N10N5LF'  | 'EP(V1)'     | ''        | 'IC'  | ''      | ''                  | 'T2C-LEO'       | 'SNI_IPB033N10N5LF.pdf'         | ''            | ''  | ''         | ''      | '20190705' | ''    
 'IPB033N10N5LF'  | 'SMLF'    | 'EMPTY'  | 'BAM10N50G01'(!)  = ''              | ''             | 'BAM10N50G01'     |'TO263_GDSXA'| 'TRANS MOS IPB033N10N5LF(100V,120A,179W)'  | 'SNI'   | 'IPB033N10N5LF'  | 'EP(V1)'     | ''        | 'IC'  | ''      | ''                  | 'T2C-LEO'       | 'SNI_IPB033N10N5LF.pdf'         | ''            | ''  | ''         | ''      | '20190705' | ''    
 'PSMN3R7-100BSE' | 'SMLF'    | 'IC'     | 'BAMN3R70000'(!)  = ''              | ''             | 'BAMN3R70000'     |'SOT404_GDSXA'| 'TRANS MOS PSMN3R7-100BSE(100V,120A,405W)' | 'NXE'   | 'PSMN3R7-100BSE' | 'EP(V1)'     | ''        | 'IC'  | ''      | ''                  | 'T2C-CARLOS'    | 'NXE_PSMN3R7-100BSE.pdf'        | ''            | ''  | ''         | ''      | '20190918' | ''    
 'PSMN3R7-100BSE' | 'SMLF'    | 'EMPTY'  | 'BAMN3R70000'(!)  = ''              | ''             | 'BAMN3R70000'     |'SOT404_GDSXA'| 'TRANS MOS PSMN3R7-100BSE(100V,120A,405W)' | 'NXE'   | 'PSMN3R7-100BSE' | 'EP(V1)'     | ''        | 'IC'  | ''      | ''                  | 'T2C-CARLOS'    | 'NXE_PSMN3R7-100BSE.pdf'        | ''            | ''  | ''         | ''      | '20190918' | ''    
 'FDN335N'        | 'SMLF'    | 'IC'     | 'BAM03350009'(!)  = ''              | ''             | 'BAM03350009'     |'SOT23_GDS_2-92X1-4'| 'TRAN MOS FDN335N(20V,1.7A 0.5W)SOT-23'    | 'FAC'   | 'FDN335N'        | 'NA'         | 'EP'      | 'IC'  | ''      | ''                  | 'S68-WT'        | 'FAC_FDN335N.pdf'               | ''            | ''  | ''         | ''      | '20191127' | ''    
 'FDN335N'        | 'SMLF'    | 'EMPTY'  | 'BAM03350009'(!)  = ''              | ''             | 'BAM03350009'     |'SOT23_GDS_2-92X1-4'| 'TRAN MOS FDN335N(20V,1.7A 0.5W)SOT-23'    | 'FAC'   | 'FDN335N'        | 'NA'         | 'EP'      | 'IC'  | ''      | ''                  | 'S68-WT'        | 'FAC_FDN335N.pdf'               | ''            | ''  | ''         | ''      | '20191127' | ''    
 'SSM3K15AMFV'    | 'SMLF'    | 'IC'     | 'BAM3K150012'(!)  = ''              | ''             | 'BAM3K150012'     |'SOT723_GDS_1-2X0-8'| 'TRAN MOS SSM3K15AMFV(30V,100MA,0.5W)'     | 'TOS'   | 'SSM3K15AMFV'    | 'EP(V1)'     | 'EP(V1)'  | 'IC'  | ''      | ''                  | 'S3D-ALAN'      | 'TOS_SSM3K15AMFV.pdf'           | ''            | ''  | ''         | ''      | '20200103' | ''    
 'SSM3K15AMFV'    | 'SMLF'    | 'EMPTY'  | 'BAM3K150012'(!)  = ''              | ''             | 'BAM3K150012'     |'SOT723_GDS_1-2X0-8'| 'TRAN MOS SSM3K15AMFV(30V,100MA,0.5W)'     | 'TOS'   | 'SSM3K15AMFV'    | 'EP(V1)'     | 'EP(V1)'  | 'IC'  | ''      | ''                  | 'S3D-ALAN'      | 'TOS_SSM3K15AMFV.pdf'           | ''            | ''  | ''         | ''      | '20200103' | ''    
 'PMV30UN2'       | 'SMLF'    | 'IC'     | 'BAM00300007'(!)  = ''              | ''             | 'BAM00300007'     |'SOT23_GDSXE'| 'TRANS MOS PMV30UN2(20V,4.2A,490MW)'       | 'NXP'   | 'PMV30UN2'       | 'EP(V1)'     | 'EP(V1)'  | 'IC'  | ''      | ''                  | 'S8A-KENNY'     | 'NXP_PMV30UN2.pdf'              | ''            | ''  | ''         | ''      | '20200305' | ''    
 'PMV30UN2'       | 'SMLF'    | 'EMPTY'  | 'BAM00300007'(!)  = ''              | ''             | 'BAM00300007'     |'SOT23_GDSXE'| 'TRANS MOS PMV30UN2(20V,4.2A,490MW)'       | 'NXP'   | 'PMV30UN2'       | 'EP(V1)'     | 'EP(V1)'  | 'IC'  | ''      | ''                  | 'S8A-KENNY'     | 'NXP_PMV30UN2.pdf'              | ''            | ''  | ''         | ''      | '20200305' | ''    
 'AOSS62934'      | 'SMLF'    | 'IC'     | 'BAM29340000'(!)  = ''              | ''             | 'BAM29340000'     |'SOT23_GDSXA'| 'TRANS MOS AOSS62934(100V,2A,1.4W)'        | 'AOS'   | 'AOSS62934'      | 'EP(V1)'     | ''        | 'IC'  | ''      | ''                  | 'F0G-MILLER'    | 'AOS_AOSS62934.pdf'             | ''            | ''  | ''         | ''      | '20200513' | ''    
 'AOSS62934'      | 'SMLF'    | 'EMPTY'  | 'BAM29340000'(!)  = ''              | ''             | 'BAM29340000'     |'SOT23_GDSXA'| 'TRANS MOS AOSS62934(100V,2A,1.4W)'        | 'AOS'   | 'AOSS62934'      | 'EP(V1)'     | ''        | 'IC'  | ''      | ''                  | 'F0G-MILLER'    | 'AOS_AOSS62934.pdf'             | ''            | ''  | ''         | ''      | '20200513' | ''    
 'ZVN3310FTA'     | 'SMLF'    | 'IC'     | 'BAM33100000'(!)  = ''              | ''             | 'BAM33100000'     |'SOT23_GDS_2-92X1-3XB'| 'TRANS MOS ZVN3310FTA(100V,0.1A,0.33W)'    | 'DDS'   | 'ZVN3310FTA'     | 'EP(V1)'     | ''        | 'IC'  | ''      | ''                  | 'S8A-YC'        | 'DDS_ZVN3310FTA.pdf'            | ''            | ''  | ''         | ''      | '20200609' | ''    
 'ZVN3310FTA'     | 'SMLF'    | 'EMPTY'  | 'BAM33100000'(!)  = ''              | ''             | 'BAM33100000'     |'SOT23_GDS_2-92X1-3XB'| 'TRANS MOS ZVN3310FTA(100V,0.1A,0.33W)'    | 'DDS'   | 'ZVN3310FTA'     | 'EP(V1)'     | ''        | 'IC'  | ''      | ''                  | 'S8A-YC'        | 'DDS_ZVN3310FTA.pdf'            | ''            | ''  | ''         | ''      | '20200609' | ''    
 'PMV213SN'       | 'SMLF'    | 'IC'     | 'BAM213S0000'(!)  = ''              | ''             | 'BAM213S0000'     |'SOT23_GDSXE'| 'TRANS MOS PMV213SN(100V,1.9A,2W)'         | 'NXE'   | 'PMV213SN'       | 'EU(V1)'     | 'EP(V1)'  | 'IC'  | ''      | ''                  | 'S9T-ANDY'      | 'NXE_PMV213SN.pdf'              | ''            | ''  | ''         | ''      | '20210312' | ''    
 'PMV213SN'       | 'SMLF'    | 'EMPTY'  | 'BAM213S0000'(!)  = ''              | ''             | 'BAM213S0000'     |'SOT23_GDSXE'| 'TRANS MOS PMV213SN(100V,1.9A,2W)'         | 'NXE'   | 'PMV213SN'       | 'EU(V1)'     | 'EP(V1)'  | 'IC'  | ''      | ''                  | 'S9T-ANDY'      | 'NXE_PMV213SN.pdf'              | ''            | ''  | ''         | ''      | '20210312' | ''    
 'IRFP1405PBF'    | 'THLF'    | 'IC'     | 'BAM14050000'(!)  = ''              | ''             | 'BAM14050000'     |'TO247AC_GDS_15-58X4-98'| 'TRANS MOS IRFP1405PBF(20V,160A,310W)'     | 'SNI'   | 'IRFP1405PBF'    | 'EP(V1)'     | ''        | 'IC'  | 'DIP'   | 'IRFP1405PBF.msg'   | 'P0A-STEVE'     | 'SNI_IRFP1405PBF.pdf'           | ''            | ''  | ''         | ''      | '20210323' | ''    
 'IRFP1405PBF'    | 'THLF'    | 'EMPTY'  | 'BAM14050000'(!)  = ''              | ''             | 'BAM14050000'     |'TO247AC_GDS_15-58X4-98'| 'TRANS MOS IRFP1405PBF(20V,160A,310W)'     | 'SNI'   | 'IRFP1405PBF'    | 'EP(V1)'     | ''        | 'IC'  | 'DIP'   | 'IRFP1405PBF.msg'   | 'P0A-STEVE'     | 'SNI_IRFP1405PBF.pdf'           | ''            | ''  | ''         | ''      | '20210323' | ''    
 'BSS138PW'       | 'SMLF'    | 'IC'     | 'BAM138PW000'(!)  = ''              | ''             | 'BAM138PW000'     |'SC70_GDS_2X1-25XA'| 'TRANS MOS BSS138PW(60V,0.32A,0.26W)'      | 'NXP'   | 'BSS138PW'       | 'EP(V1)'     | 'EP(V1)'  | 'IC'  | ''      | ''                  | 'T2HV-EASON'    | 'NXP_BSS138PW.pdf'              | ''            | ''  | ''         | ''      | '20210331' | ''    
 'BSS138PW'       | 'SMLF'    | 'EMPTY'  | 'BAM138PW000'(!)  = ''              | ''             | 'BAM138PW000'     |'SC70_GDS_2X1-25XA'| 'TRANS MOS BSS138PW(60V,0.32A,0.26W)'      | 'NXP'   | 'BSS138PW'       | 'EP(V1)'     | 'EP(V1)'  | 'IC'  | ''      | ''                  | 'T2HV-EASON'    | 'NXP_BSS138PW.pdf'              | ''            | ''  | ''         | ''      | '20210331' | ''    
 'DMN3042L-7'     | 'SMLF'    | 'IC'     | 'BAM30420000'(!)  = ''              | ''             | 'BAM30420000'     |'SOT23_GDSXC'| 'TRANS MOS DMN3042L-7(30V,5.8A,0.72W)'     | 'DDS'   | 'DMN3042L-7'     | 'EP(V1)'     | 'EP(V1)'  | 'IC'  | ''      | ''                  | 'S9T-DAVID'     | 'DDS_DMN3042L-7.pdf'            | ''            | ''  | ''         | ''      | '20210426' | ''    
 'DMN3042L-7'     | 'SMLF'    | 'EMPTY'  | 'BAM30420000'(!)  = ''              | ''             | 'BAM30420000'     |'SOT23_GDSXC'| 'TRANS MOS DMN3042L-7(30V,5.8A,0.72W)'     | 'DDS'   | 'DMN3042L-7'     | 'EP(V1)'     | 'EP(V1)'  | 'IC'  | ''      | ''                  | 'S9T-DAVID'     | 'DDS_DMN3042L-7.pdf'            | ''            | ''  | ''         | ''      | '20210426' | ''    
 'PSMN7R6-100BSE' | 'SMLF'    | 'IC'     | 'BAMN7R60000'(!)  = ''              | ''             | 'BAMN7R60000'     |'SOT404_GDSXA'| 'TRANS MOS PSMN7R6-100BSE(100V,75A,296W)'  | 'NXP'   | 'PSMN7R6-100BSE' | 'EU(V1)'     | 'EU(V1)'  | 'IC'  | ''      | ''                  | 'S1L-HUNTER'    | 'NXP_PSMN7R6-100BSE.pdf'        | ''            | ''  | ''         | ''      | '20210819' | ''    
 'PSMN7R6-100BSE' | 'SMLF'    | 'EMPTY'  | 'BAMN7R60000'(!)  = ''              | ''             | 'BAMN7R60000'     |'SOT404_GDSXA'| 'TRANS MOS PSMN7R6-100BSE(100V,75A,296W)'  | 'NXP'   | 'PSMN7R6-100BSE' | 'EU(V1)'     | 'EU(V1)'  | 'IC'  | ''      | ''                  | 'S1L-HUNTER'    | 'NXP_PSMN7R6-100BSE.pdf'        | ''            | ''  | ''         | ''      | '20210819' | ''    
 'BSS138W'        | 'SMLF'    | 'IC'     | 'BAM01380043'(!)  = ''              | ''             | 'BAM01380043'     |'SOT323_GDS_2X1-25XA'| 'TRANS MOSFET BSS138W(60V,0.28A,0.5W)AEC'  | 'SNI'   | 'BSS138W'        | 'EP(V1)'     | ''        | 'IC'  | ''      | 'BSS138W.msg'       | 'JG8-COPEER'    | 'SNI_BSS138W.pdf'               | ''            | ''  | ''         | ''      | '20210924' | ''    
 'BSS138W'        | 'SMLF'    | 'EMPTY'  | 'BAM01380043'(!)  = ''              | ''             | 'BAM01380043'     |'SOT323_GDS_2X1-25XA'| 'TRANS MOSFET BSS138W(60V,0.28A,0.5W)AEC'  | 'SNI'   | 'BSS138W'        | 'EP(V1)'     | ''        | 'IC'  | ''      | 'BSS138W.msg'       | 'JG8-COPEER'    | 'SNI_BSS138W.pdf'               | ''            | ''  | ''         | ''      | '20210924' | ''    
 'IXTH80N075L2'   | 'THLF'    | 'IC'     | 'BAM80N00000'(!)  = ''              | ''             | 'BAM80N00000'     |'TO247_GDS_15-94X5-02'| 'TRANS MOS DIP IXTH80N075L2(75V,80A,357W)' | 'LFI'   | 'IXTH80N075L2'   | 'EP(V1)'     | ''        | 'IC'  | 'DIP'   | 'IXTH80N075L2.msg'  | 'A7M-ROD'       | 'LFI_IXTH80N075L2.pdf'          | ''            | ''  | ''         | ''      | '20210930' | ''    
 'IXTH80N075L2'   | 'THLF'    | 'EMPTY'  | 'BAM80N00000'(!)  = ''              | ''             | 'BAM80N00000'     |'TO247_GDS_15-94X5-02'| 'TRANS MOS DIP IXTH80N075L2(75V,80A,357W)' | 'LFI'   | 'IXTH80N075L2'   | 'EP(V1)'     | ''        | 'IC'  | 'DIP'   | 'IXTH80N075L2.msg'  | 'A7M-ROD'       | 'LFI_IXTH80N075L2.pdf'          | ''            | ''  | ''         | ''      | '20210930' | ''    
 'IXTH140N075L2'  | 'THLF'    | 'IC'     | 'BAM140N0000'(!)  = ''              | ''             | 'BAM140N0000'     |'TO247_GDS_15-94X5-02'| 'TRANS MOS DIP IXTH140N075(75V,140A,540W)' | 'LFI'   | 'IXTH140N075L2'  | 'EP(V1)'     | ''        | 'IC'  | 'DIP'   | 'IXTH140N075L2.msg' | 'A7M-ROD'       | 'LFI_IXTH140N075L2.pdf'         | ''            | ''  | ''         | ''      | '20211001' | ''    
 'IXTH140N075L2'  | 'THLF'    | 'EMPTY'  | 'BAM140N0000'(!)  = ''              | ''             | 'BAM140N0000'     |'TO247_GDS_15-94X5-02'| 'TRANS MOS DIP IXTH140N075(75V,140A,540W)' | 'LFI'   | 'IXTH140N075L2'  | 'EP(V1)'     | ''        | 'IC'  | 'DIP'   | 'IXTH140N075L2.msg' | 'A7M-ROD'       | 'LFI_IXTH140N075L2.pdf'         | ''            | ''  | ''         | ''      | '20211001' | ''    
 'NX138BK'        | 'SMLF'    | 'IC'     | 'BAM01380044'(!)  = ''              | ''             | 'BAM01380044'     |'SOT23_GDSXE'| 'TRANS MOS NX138BK(60V,0.265A,0.31W)'      | 'NXE'   | 'NX138BK'        | 'EP(V1)'     | 'EP(V1)'  | 'IC'  | ''      | 'NX138BK.msg'       | 'MF6-LIAM'      | 'NXE_NX138BK.pdf'               | ''            | ''  | ''         | ''      | '20221228' | ''    
 'NX138BK'        | 'SMLF'    | 'EMPTY'  | 'BAM01380044'(!)  = ''              | ''             | 'BAM01380044'     |'SOT23_GDSXE'| 'TRANS MOS NX138BK(60V,0.265A,0.31W)'      | 'NXE'   | 'NX138BK'        | 'EP(V1)'     | 'EP(V1)'  | 'IC'  | ''      | 'NX138BK.msg'       | 'MF6-LIAM'      | 'NXE_NX138BK.pdf'               | ''            | ''  | ''         | ''      | '20221228' | ''    
 'PMV30UN2'       | 'SMLF'    | 'IC'     | 'BAM00300007SEL1'(!) = ''               | ''               | 'BAM00300007SEL1' |'SOT23_GDSXE'| 'TRANS MOS PMV30UN2(20V,4.2A,0.49W)SELASN' | 'NXP'   | 'PMV30UN2'       | 'EP(V1)'     | 'EP(V1)'  | 'IC'  | ''      | 'SEL_15QPN.xlsx'    | 'S8A-KENNY'     | 'NXP_PMV30UN2.pdf'              | ''            | ''  | ''         | ''      | '20230627' | ''    
 'PMV30UN2'       | 'SMLF'    | 'EMPTY'  | 'BAM00300007SEL1'(!) = ''               | ''               | 'BAM00300007SEL1' |'SOT23_GDSXE'| 'TRANS MOS PMV30UN2(20V,4.2A,0.49W)SELASN' | 'NXP'   | 'PMV30UN2'       | 'EP(V1)'     | 'EP(V1)'  | 'IC'  | ''      | 'SEL_15QPN.xlsx'    | 'S8A-KENNY'     | 'NXP_PMV30UN2.pdf'              | ''            | ''  | ''         | ''      | '20230627' | ''    
 'DMG6968U-7'     | 'SMLF'    | 'IC'     | 'BAM69680000SEL1'(!) = ''              | ''               | 'BAM69680000SEL1' |'SOT23_GDSXC'| 'TRANS MOS DMG6968U(20V6.5A1.3W)SOT23SELA' | 'DDS'   | 'DMG6968U-7'     | 'EP(V1)'     | ''        | 'IC'  | ''      | 'SEL_15QPN.xlsx'    | 'S1N-AI-JU'     | 'DDS_DMG6968U.pdf'              | ''            | ''  | ''         | ''      | '20230626' | ''    
 'DMG6968U-7'     | 'SMLF'    | 'EMPTY'  | 'BAM69680000SEL1'(!) = ''              | ''               | 'BAM69680000SEL1' |'SOT23_GDSXC'| 'TRANS MOS DMG6968U(20V6.5A1.3W)SOT23SELA' | 'DDS'   | 'DMG6968U-7'     | 'EP(V1)'     | ''        | 'IC'  | ''      | 'SEL_15QPN.xlsx'    | 'S1N-AI-JU'     | 'DDS_DMG6968U.pdf'              | ''            | ''  | ''         | ''      | '20230626' | ''    
 'PSMN3R7-100BSE' | 'SMLF'    | 'IC'     | 'BAMN3R70000SEL1'(!) = ''              | ''               | 'BAMN3R70000SEL1' |'SOT404_GDSXA'| 'TRANS MOS PSMN3R7-100B(100V120A405W)SELA' | 'NXE'   | 'PSMN3R7-100BSE' | 'EP(V1)'     | ''        | 'IC'  | ''      | 'SEL_15QPN.xlsx'    | 'S8I-CARLOS'    | 'NXE_PSMN3R7-100BSE.pdf'        | ''            | ''  | ''         | ''      | '20230626' | ''    
 'PSMN3R7-100BSE' | 'SMLF'    | 'EMPTY'  | 'BAMN3R70000SEL1'(!) = ''              | ''               | 'BAMN3R70000SEL1' |'SOT404_GDSXA'| 'TRANS MOS PSMN3R7-100B(100V120A405W)SELA' | 'NXE'   | 'PSMN3R7-100BSE' | 'EP(V1)'     | ''        | 'IC'  | ''      | 'SEL_15QPN.xlsx'    | 'S8I-CARLOS'    | 'NXE_PSMN3R7-100BSE.pdf'        | ''            | ''  | ''         | ''      | '20230626' | ''    

END_PART

END.

